(kicad_pcb
	(version 20260206)
	(generator "pcbnew")
	(generator_version "10.0")
	(general
		(thickness 1.6)
		(legacy_teardrops no)
	)
	(paper "A4")
	(title_block
		(title "01162023_DA0F0TEBIF0_F0T_Expander_BD_F_brd_V02_OCP.brd")
		(comment 1 "Grand Teton / footprints 8339-8346 of 9728")
	)
	(layers
		(0 "F.Cu" signal "TOP")
		(4 "In1.Cu" signal "GND")
		(6 "In2.Cu" signal "VCC")
		(8 "In3.Cu" signal "VCC1")
		(10 "In4.Cu" signal "GND1")
		(12 "In5.Cu" signal "IN1")
		(14 "In6.Cu" signal "GND2")
		(16 "In7.Cu" signal "IN2")
		(18 "In8.Cu" signal "GND3")
		(20 "In9.Cu" signal "IN3")
		(22 "In10.Cu" signal "GND4")
		(24 "In11.Cu" signal "IN4")
		(26 "In12.Cu" signal "GND5")
		(28 "In13.Cu" signal "IN5")
		(30 "In14.Cu" signal "GND6")
		(32 "In15.Cu" signal "IN6")
		(34 "In16.Cu" signal "GND7")
		(2 "B.Cu" signal "BOTTOM")
		(9 "F.Adhes" user "F.Adhesive")
		(11 "B.Adhes" user "B.Adhesive")
		(13 "F.Paste" user "Package Geometry/Pastemask Top")
		(15 "B.Paste" user "Package Geometry/Pastemask Bottom")
		(5 "F.SilkS" user "Ref Des/Silkscreen Top")
		(7 "B.SilkS" user "Ref Des/Silkscreen Bottom")
		(1 "F.Mask" user "Board Geometry/Soldermask Top")
		(3 "B.Mask" user "Board Geometry/Soldermask Bottom")
		(17 "Dwgs.User" user "User.Drawings")
		(19 "Cmts.User" user "User.Comments")
		(21 "Eco1.User" user "User.Eco1")
		(23 "Eco2.User" user "User.Eco2")
		(25 "Edge.Cuts" user "Board Geometry/Outline")
		(27 "Margin" user)
		(31 "F.CrtYd" user "Package Geometry/Place Bound Top")
		(29 "B.CrtYd" user "Package Geometry/Place Bound Bottom")
		(35 "F.Fab" user "Ref Des/Assembly Top")
		(33 "B.Fab" user "Ref Des/Assembly Bottom")
	)
	(footprint ""
		(layer "B.Cu")
		(at 115.935252 -325.180706 -90)
		(property "Reference" "C4203"
			(at 0 0 90)
			(layer "B.SilkS")
			(hide yes)
			(effects
				(font
					(size 1.27 1.27)
				)
				(justify mirror)
			)
		)
		(property "Value" ""
			(at 0 0 90)
			(layer "B.Fab")
			(effects
				(font
					(size 1.27 1.27)
				)
				(justify mirror)
			)
		)
		(duplicate_pad_numbers_are_jumpers no)
		(fp_line
			(start -1.2954 0.5842)
			(end 1.2954 0.5842)
			(stroke
				(width 0.1524)
				(type default)
			)
			(layer "B.SilkS")
		)
		(fp_line
			(start 1.2954 0.5842)
			(end 1.2954 -0.5842)
			(stroke
				(width 0.1524)
				(type default)
			)
			(layer "B.SilkS")
		)
		(fp_line
			(start -1.2954 -0.5842)
			(end -1.2954 0.5842)
			(stroke
				(width 0.1524)
				(type default)
			)
			(layer "B.SilkS")
		)
		(fp_line
			(start 1.2954 -0.5842)
			(end -1.2954 -0.5842)
			(stroke
				(width 0.1524)
				(type default)
			)
			(layer "B.SilkS")
		)
		(fp_line
			(start -0.8636 0.4572)
			(end 0.8636 0.4572)
			(stroke
				(width 0.1)
				(type default)
			)
			(layer "B.Fab")
		)
		(fp_line
			(start 0.8636 0.4572)
			(end 0.8636 0.4064)
			(stroke
				(width 0.1)
				(type default)
			)
			(layer "B.Fab")
		)
		(fp_line
			(start -1.1938 0.4064)
			(end -0.8636 0.4064)
			(stroke
				(width 0.1)
				(type default)
			)
			(layer "B.Fab")
		)
		(fp_line
			(start -0.8636 0.4064)
			(end -0.8636 0.4572)
			(stroke
				(width 0.1)
				(type default)
			)
			(layer "B.Fab")
		)
		(fp_line
			(start 0.8636 0.4064)
			(end 1.1938 0.4064)
			(stroke
				(width 0.1)
				(type default)
			)
			(layer "B.Fab")
		)
		(fp_line
			(start 1.1938 0.4064)
			(end 1.1938 -0.4064)
			(stroke
				(width 0.1)
				(type default)
			)
			(layer "B.Fab")
		)
		(fp_line
			(start -1.1938 -0.4064)
			(end -1.1938 0.4064)
			(stroke
				(width 0.1)
				(type default)
			)
			(layer "B.Fab")
		)
		(fp_line
			(start -0.8636 -0.4064)
			(end -1.1938 -0.4064)
			(stroke
				(width 0.1)
				(type default)
			)
			(layer "B.Fab")
		)
		(fp_line
			(start 0.8636 -0.4064)
			(end 0.8636 -0.4572)
			(stroke
				(width 0.1)
				(type default)
			)
			(layer "B.Fab")
		)
		(fp_line
			(start 1.1938 -0.4064)
			(end 0.8636 -0.4064)
			(stroke
				(width 0.1)
				(type default)
			)
			(layer "B.Fab")
		)
		(fp_line
			(start -0.8636 -0.4572)
			(end -0.8636 -0.4064)
			(stroke
				(width 0.1)
				(type default)
			)
			(layer "B.Fab")
		)
		(fp_line
			(start 0.8636 -0.4572)
			(end -0.8636 -0.4572)
			(stroke
				(width 0.1)
				(type default)
			)
			(layer "B.Fab")
		)
		(pad "1" smd rect
			(at 0.7366 0 180)
			(size 0.7112 0.8128)
			(layers "B.Cu" "B.Mask" "B.Paste")
			(net "P0V8_SERDES_VDDA_PEX0_C1")
		)
		(pad "2" smd rect
			(at -0.7366 0 180)
			(size 0.7112 0.8128)
			(layers "B.Cu" "B.Mask" "B.Paste")
			(net "GND")
		)
	)
	(footprint ""
		(layer "B.Cu")
		(at 339.575902 -308.746398 90)
		(property "Reference" "C4321"
			(at 0 0 90)
			(layer "B.SilkS")
			(hide yes)
			(effects
				(font
					(size 1.27 1.27)
				)
				(justify mirror)
			)
		)
		(property "Value" ""
			(at 0 0 90)
			(layer "B.Fab")
			(effects
				(font
					(size 1.27 1.27)
				)
				(justify mirror)
			)
		)
		(duplicate_pad_numbers_are_jumpers no)
		(fp_line
			(start 0.299974 -0.150114)
			(end -0.299974 -0.150114)
			(stroke
				(width 0.1)
				(type default)
			)
			(layer "B.Fab")
		)
		(fp_line
			(start -0.299974 -0.150114)
			(end -0.299974 0.150114)
			(stroke
				(width 0.1)
				(type default)
			)
			(layer "B.Fab")
		)
		(fp_line
			(start 0.299974 0.150114)
			(end 0.299974 -0.150114)
			(stroke
				(width 0.1)
				(type default)
			)
			(layer "B.Fab")
		)
		(fp_line
			(start -0.299974 0.150114)
			(end 0.299974 0.150114)
			(stroke
				(width 0.1)
				(type default)
			)
			(layer "B.Fab")
		)
		(pad "1" smd rect
			(at 0.2667 0 270)
			(size 0.3048 0.381)
			(layers "B.Cu" "B.Mask" "B.Paste")
			(net "P0V8_PEX2")
		)
		(pad "2" smd rect
			(at -0.2667 0 270)
			(size 0.3048 0.381)
			(layers "B.Cu" "B.Mask" "B.Paste")
			(net "GND")
		)
	)
	(footprint ""
		(layer "B.Cu")
		(at 399.400014 -301.599854 -90)
		(property "Reference" "C1957"
			(at 0 0 90)
			(layer "B.SilkS")
			(hide yes)
			(effects
				(font
					(size 1.27 1.27)
				)
				(justify mirror)
			)
		)
		(property "Value" ""
			(at 0 0 90)
			(layer "B.Fab")
			(effects
				(font
					(size 1.27 1.27)
				)
				(justify mirror)
			)
		)
		(duplicate_pad_numbers_are_jumpers no)
		(fp_line
			(start -0.299974 0.150114)
			(end 0.299974 0.150114)
			(stroke
				(width 0.1)
				(type default)
			)
			(layer "B.Fab")
		)
		(fp_line
			(start 0.299974 0.150114)
			(end 0.299974 -0.150114)
			(stroke
				(width 0.1)
				(type default)
			)
			(layer "B.Fab")
		)
		(fp_line
			(start -0.299974 -0.150114)
			(end -0.299974 0.150114)
			(stroke
				(width 0.1)
				(type default)
			)
			(layer "B.Fab")
		)
		(fp_line
			(start 0.299974 -0.150114)
			(end -0.299974 -0.150114)
			(stroke
				(width 0.1)
				(type default)
			)
			(layer "B.Fab")
		)
		(pad "1" smd rect
			(at 0.2667 0 90)
			(size 0.3048 0.381)
			(layers "B.Cu" "B.Mask" "B.Paste")
			(net "P0V8_SERDES_VDDA_PEX3")
		)
		(pad "2" smd rect
			(at -0.2667 0 90)
			(size 0.3048 0.381)
			(layers "B.Cu" "B.Mask" "B.Paste")
			(net "GND")
		)
	)
	(footprint ""
		(layer "B.Cu")
		(at 201.088244 -259.311648 -90)
		(property "Reference" "R6340"
			(at 0 0 90)
			(layer "B.SilkS")
			(hide yes)
			(effects
				(font
					(size 1.27 1.27)
				)
				(justify mirror)
			)
		)
		(property "Value" ""
			(at 0 0 90)
			(layer "B.Fab")
			(effects
				(font
					(size 1.27 1.27)
				)
				(justify mirror)
			)
		)
		(duplicate_pad_numbers_are_jumpers no)
		(fp_line
			(start -0.7874 0.4064)
			(end 0.7874 0.4064)
			(stroke
				(width 0.1524)
				(type default)
			)
			(layer "B.SilkS")
		)
		(fp_line
			(start 0.7874 0.4064)
			(end 0.7874 -0.4064)
			(stroke
				(width 0.1524)
				(type default)
			)
			(layer "B.SilkS")
		)
		(fp_line
			(start -0.7874 -0.4064)
			(end -0.7874 0.4064)
			(stroke
				(width 0.1524)
				(type default)
			)
			(layer "B.SilkS")
		)
		(fp_line
			(start 0.7874 -0.4064)
			(end -0.7874 -0.4064)
			(stroke
				(width 0.1524)
				(type default)
			)
			(layer "B.SilkS")
		)
		(fp_line
			(start -0.67945 0.3048)
			(end -0.120396 0.3048)
			(stroke
				(width 0.1)
				(type default)
			)
			(layer "B.Fab")
		)
		(fp_line
			(start -0.120396 0.3048)
			(end -0.120396 0.2794)
			(stroke
				(width 0.1)
				(type default)
			)
			(layer "B.Fab")
		)
		(fp_line
			(start 0.12065 0.3048)
			(end 0.67945 0.3048)
			(stroke
				(width 0.1)
				(type default)
			)
			(layer "B.Fab")
		)
		(fp_line
			(start 0.67945 0.3048)
			(end 0.67945 -0.305054)
			(stroke
				(width 0.1)
				(type default)
			)
			(layer "B.Fab")
		)
		(fp_line
			(start -0.120396 0.2794)
			(end 0.12065 0.2794)
			(stroke
				(width 0.1)
				(type default)
			)
			(layer "B.Fab")
		)
		(fp_line
			(start 0.12065 0.2794)
			(end 0.12065 0.3048)
			(stroke
				(width 0.1)
				(type default)
			)
			(layer "B.Fab")
		)
		(fp_line
			(start -0.12065 -0.2794)
			(end -0.12065 -0.3048)
			(stroke
				(width 0.1)
				(type default)
			)
			(layer "B.Fab")
		)
		(fp_line
			(start 0.12065 -0.2794)
			(end -0.12065 -0.2794)
			(stroke
				(width 0.1)
				(type default)
			)
			(layer "B.Fab")
		)
		(fp_line
			(start -0.67945 -0.3048)
			(end -0.67945 0.3048)
			(stroke
				(width 0.1)
				(type default)
			)
			(layer "B.Fab")
		)
		(fp_line
			(start -0.12065 -0.3048)
			(end -0.67945 -0.3048)
			(stroke
				(width 0.1)
				(type default)
			)
			(layer "B.Fab")
		)
		(fp_line
			(start 0.12065 -0.305054)
			(end 0.12065 -0.2794)
			(stroke
				(width 0.1)
				(type default)
			)
			(layer "B.Fab")
		)
		(fp_line
			(start 0.67945 -0.305054)
			(end 0.12065 -0.305054)
			(stroke
				(width 0.1)
				(type default)
			)
			(layer "B.Fab")
		)
		(pad "1" smd circle
			(at 0.40005 0 90)
			(size 0 0)
			(layers "B.Cu" "B.Mask" "B.Paste")
			(net "PEX_MUX_A1")
		)
		(pad "2" smd circle
			(at -0.40005 0 90)
			(size 0 0)
			(layers "B.Cu" "B.Mask" "B.Paste")
			(net "GND")
		)
	)
	(footprint ""
		(layer "B.Cu")
		(at 252.70968 -83.554316 -90)
		(property "Reference" "C2638"
			(at 0 0 90)
			(layer "B.SilkS")
			(hide yes)
			(effects
				(font
					(size 1.27 1.27)
				)
				(justify mirror)
			)
		)
		(property "Value" ""
			(at 0 0 90)
			(layer "B.Fab")
			(effects
				(font
					(size 1.27 1.27)
				)
				(justify mirror)
			)
		)
		(duplicate_pad_numbers_are_jumpers no)
		(fp_line
			(start -1.2954 0.5842)
			(end 1.2954 0.5842)
			(stroke
				(width 0.1524)
				(type default)
			)
			(layer "B.SilkS")
		)
		(fp_line
			(start 1.2954 0.5842)
			(end 1.2954 -0.5842)
			(stroke
				(width 0.1524)
				(type default)
			)
			(layer "B.SilkS")
		)
		(fp_line
			(start -1.2954 -0.5842)
			(end -1.2954 0.5842)
			(stroke
				(width 0.1524)
				(type default)
			)
			(layer "B.SilkS")
		)
		(fp_line
			(start 1.2954 -0.5842)
			(end -1.2954 -0.5842)
			(stroke
				(width 0.1524)
				(type default)
			)
			(layer "B.SilkS")
		)
		(fp_line
			(start -0.8636 0.4572)
			(end 0.8636 0.4572)
			(stroke
				(width 0.1)
				(type default)
			)
			(layer "B.Fab")
		)
		(fp_line
			(start 0.8636 0.4572)
			(end 0.8636 0.4064)
			(stroke
				(width 0.1)
				(type default)
			)
			(layer "B.Fab")
		)
		(fp_line
			(start -1.1938 0.4064)
			(end -0.8636 0.4064)
			(stroke
				(width 0.1)
				(type default)
			)
			(layer "B.Fab")
		)
		(fp_line
			(start -0.8636 0.4064)
			(end -0.8636 0.4572)
			(stroke
				(width 0.1)
				(type default)
			)
			(layer "B.Fab")
		)
		(fp_line
			(start 0.8636 0.4064)
			(end 1.1938 0.4064)
			(stroke
				(width 0.1)
				(type default)
			)
			(layer "B.Fab")
		)
		(fp_line
			(start 1.1938 0.4064)
			(end 1.1938 -0.4064)
			(stroke
				(width 0.1)
				(type default)
			)
			(layer "B.Fab")
		)
		(fp_line
			(start -1.1938 -0.4064)
			(end -1.1938 0.4064)
			(stroke
				(width 0.1)
				(type default)
			)
			(layer "B.Fab")
		)
		(fp_line
			(start -0.8636 -0.4064)
			(end -1.1938 -0.4064)
			(stroke
				(width 0.1)
				(type default)
			)
			(layer "B.Fab")
		)
		(fp_line
			(start 0.8636 -0.4064)
			(end 0.8636 -0.4572)
			(stroke
				(width 0.1)
				(type default)
			)
			(layer "B.Fab")
		)
		(fp_line
			(start 1.1938 -0.4064)
			(end 0.8636 -0.4064)
			(stroke
				(width 0.1)
				(type default)
			)
			(layer "B.Fab")
		)
		(fp_line
			(start -0.8636 -0.4572)
			(end -0.8636 -0.4064)
			(stroke
				(width 0.1)
				(type default)
			)
			(layer "B.Fab")
		)
		(fp_line
			(start 0.8636 -0.4572)
			(end -0.8636 -0.4572)
			(stroke
				(width 0.1)
				(type default)
			)
			(layer "B.Fab")
		)
		(pad "1" smd rect
			(at 0.7366 0 180)
			(size 0.7112 0.8128)
			(layers "B.Cu" "B.Mask" "B.Paste")
			(net "P3V3_CLK_GEN_VDDXTAL_CK440")
		)
		(pad "2" smd rect
			(at -0.7366 0 180)
			(size 0.7112 0.8128)
			(layers "B.Cu" "B.Mask" "B.Paste")
			(net "GND")
		)
	)
	(footprint ""
		(layer "B.Cu")
		(at 172.900086 -290.199826 90)
		(property "Reference" "C1485"
			(at 0 0 90)
			(layer "B.SilkS")
			(hide yes)
			(effects
				(font
					(size 1.27 1.27)
				)
				(justify mirror)
			)
		)
		(property "Value" ""
			(at 0 0 90)
			(layer "B.Fab")
			(effects
				(font
					(size 1.27 1.27)
				)
				(justify mirror)
			)
		)
		(duplicate_pad_numbers_are_jumpers no)
		(fp_line
			(start 0.299974 -0.150114)
			(end -0.299974 -0.150114)
			(stroke
				(width 0.1)
				(type default)
			)
			(layer "B.Fab")
		)
		(fp_line
			(start -0.299974 -0.150114)
			(end -0.299974 0.150114)
			(stroke
				(width 0.1)
				(type default)
			)
			(layer "B.Fab")
		)
		(fp_line
			(start 0.299974 0.150114)
			(end 0.299974 -0.150114)
			(stroke
				(width 0.1)
				(type default)
			)
			(layer "B.Fab")
		)
		(fp_line
			(start -0.299974 0.150114)
			(end 0.299974 0.150114)
			(stroke
				(width 0.1)
				(type default)
			)
			(layer "B.Fab")
		)
		(pad "1" smd rect
			(at 0.2667 0 270)
			(size 0.3048 0.381)
			(layers "B.Cu" "B.Mask" "B.Paste")
			(net "P0V8_SERDES_VDDA_PEX1")
		)
		(pad "2" smd rect
			(at -0.2667 0 270)
			(size 0.3048 0.381)
			(layers "B.Cu" "B.Mask" "B.Paste")
			(net "GND")
		)
	)
	(footprint ""
		(layer "B.Cu")
		(at 98.292412 -352.735388 180)
		(property "Reference" "R6375"
			(at 0 0 0)
			(layer "B.SilkS")
			(hide yes)
			(effects
				(font
					(size 1.27 1.27)
				)
				(justify mirror)
			)
		)
		(property "Value" ""
			(at 0 0 0)
			(layer "B.Fab")
			(effects
				(font
					(size 1.27 1.27)
				)
				(justify mirror)
			)
		)
		(duplicate_pad_numbers_are_jumpers no)
		(fp_line
			(start 0.7874 0.4064)
			(end 0.7874 -0.4064)
			(stroke
				(width 0.1524)
				(type default)
			)
			(layer "B.SilkS")
		)
		(fp_line
			(start 0.7874 -0.4064)
			(end -0.7874 -0.4064)
			(stroke
				(width 0.1524)
				(type default)
			)
			(layer "B.SilkS")
		)
		(fp_line
			(start -0.7874 0.4064)
			(end 0.7874 0.4064)
			(stroke
				(width 0.1524)
				(type default)
			)
			(layer "B.SilkS")
		)
		(fp_line
			(start -0.7874 -0.4064)
			(end -0.7874 0.4064)
			(stroke
				(width 0.1524)
				(type default)
			)
			(layer "B.SilkS")
		)
		(fp_line
			(start 0.67945 0.3048)
			(end 0.67945 -0.305054)
			(stroke
				(width 0.1)
				(type default)
			)
			(layer "B.Fab")
		)
		(fp_line
			(start 0.67945 -0.305054)
			(end 0.12065 -0.305054)
			(stroke
				(width 0.1)
				(type default)
			)
			(layer "B.Fab")
		)
		(fp_line
			(start 0.12065 0.3048)
			(end 0.67945 0.3048)
			(stroke
				(width 0.1)
				(type default)
			)
			(layer "B.Fab")
		)
		(fp_line
			(start 0.12065 0.2794)
			(end 0.12065 0.3048)
			(stroke
				(width 0.1)
				(type default)
			)
			(layer "B.Fab")
		)
		(fp_line
			(start 0.12065 -0.2794)
			(end -0.12065 -0.2794)
			(stroke
				(width 0.1)
				(type default)
			)
			(layer "B.Fab")
		)
		(fp_line
			(start 0.12065 -0.305054)
			(end 0.12065 -0.2794)
			(stroke
				(width 0.1)
				(type default)
			)
			(layer "B.Fab")
		)
		(fp_line
			(start -0.120396 0.3048)
			(end -0.120396 0.2794)
			(stroke
				(width 0.1)
				(type default)
			)
			(layer "B.Fab")
		)
		(fp_line
			(start -0.120396 0.2794)
			(end 0.12065 0.2794)
			(stroke
				(width 0.1)
				(type default)
			)
			(layer "B.Fab")
		)
		(fp_line
			(start -0.12065 -0.2794)
			(end -0.12065 -0.3048)
			(stroke
				(width 0.1)
				(type default)
			)
			(layer "B.Fab")
		)
		(fp_line
			(start -0.12065 -0.3048)
			(end -0.67945 -0.3048)
			(stroke
				(width 0.1)
				(type default)
			)
			(layer "B.Fab")
		)
		(fp_line
			(start -0.67945 0.3048)
			(end -0.120396 0.3048)
			(stroke
				(width 0.1)
				(type default)
			)
			(layer "B.Fab")
		)
		(fp_line
			(start -0.67945 -0.3048)
			(end -0.67945 0.3048)
			(stroke
				(width 0.1)
				(type default)
			)
			(layer "B.Fab")
		)
		(pad "1" smd circle
			(at 0.40005 0)
			(size 0 0)
			(layers "B.Cu" "B.Mask" "B.Paste")
			(net "CLK_100M_DB800ZL_PEX0_S3_R_DN")
		)
		(pad "2" smd circle
			(at -0.40005 0)
			(size 0 0)
			(layers "B.Cu" "B.Mask" "B.Paste")
			(net "CLK_100M_DB800ZL_PEX0_S3_DN")
		)
	)
	(footprint ""
		(layer "B.Cu")
		(at 69.149976 -294.4749 180)
		(property "Reference" "C1163"
			(at 0 0 0)
			(layer "B.SilkS")
			(hide yes)
			(effects
				(font
					(size 1.27 1.27)
				)
				(justify mirror)
			)
		)
		(property "Value" ""
			(at 0 0 0)
			(layer "B.Fab")
			(effects
				(font
					(size 1.27 1.27)
				)
				(justify mirror)
			)
		)
		(duplicate_pad_numbers_are_jumpers no)
		(fp_line
			(start 0.299974 0.150114)
			(end 0.299974 -0.150114)
			(stroke
				(width 0.1)
				(type default)
			)
			(layer "B.Fab")
		)
		(fp_line
			(start 0.299974 -0.150114)
			(end -0.299974 -0.150114)
			(stroke
				(width 0.1)
				(type default)
			)
			(layer "B.Fab")
		)
		(fp_line
			(start -0.299974 0.150114)
			(end 0.299974 0.150114)
			(stroke
				(width 0.1)
				(type default)
			)
			(layer "B.Fab")
		)
		(fp_line
			(start -0.299974 -0.150114)
			(end -0.299974 0.150114)
			(stroke
				(width 0.1)
				(type default)
			)
			(layer "B.Fab")
		)
		(pad "1" smd rect
			(at 0.2667 0)
			(size 0.3048 0.381)
			(layers "B.Cu" "B.Mask" "B.Paste")
			(net "P0V8_SERDES_VDDA_PEX0")
		)
		(pad "2" smd rect
			(at -0.2667 0)
			(size 0.3048 0.381)
			(layers "B.Cu" "B.Mask" "B.Paste")
			(net "GND")
		)
	)
)
